# T6G (Grand Teton) — schematic netlist excerpt (pin names and nets, part order shuffled) for the footprints in the layout excerpt that follows; sources: Cadence DE-HDL packaged netlist, KiCad conversion of 04192023_DAF0TMB3IC0_F0TG_MB_C_brd_V02_OCP.brd

C515  Q_CAP  0.1UF 10V 10% X7S  pkg C0201  page 279 : A = P1V8_CPU0_RT0_1A ; B = GND
C454  Q_CAP  1UF 4V 20% X6S  pkg 0201  page 356 : A = P0V9_CPU1_RT_2D ; B = GND
C6105  Q_CAP  10UF 25V 10% X6S  pkg C0805  page 179 : A = P1V2_CPU0_USB2_DVDD12 ; B = GND
R3132  Q_RES  100K 1% CHIP  pkg 0402LF  page 131 : A = GND ; B = FM_OCP_SFF_PWR_GOOD

(kicad_pcb
	(version 20260206)
	(generator "pcbnew")
	(generator_version "10.0")
	(general
		(thickness 1.6)
		(legacy_teardrops no)
	)
	(paper "A4")
	(title_block
		(title "04192023_DAF0TMB3IC0_F0TG_MB_C_brd_V02_OCP.brd")
		(comment 1 "Grand Teton / footprints 6058-6061 of 8354")
	)
	(layers
		(0 "F.Cu" signal "TOP")
		(4 "In1.Cu" signal "GND")
		(6 "In2.Cu" signal "IN1")
		(8 "In3.Cu" signal "GND1")
		(10 "In4.Cu" signal "IN2")
		(12 "In5.Cu" signal "GND2")
		(14 "In6.Cu" signal "IN3")
		(16 "In7.Cu" signal "GND3")
		(18 "In8.Cu" signal "VCC")
		(20 "In9.Cu" signal "VCC1")
		(22 "In10.Cu" signal "GND4")
		(24 "In11.Cu" signal "IN4")
		(26 "In12.Cu" signal "GND5")
		(28 "In13.Cu" signal "IN5")
		(30 "In14.Cu" signal "GND6")
		(32 "In15.Cu" signal "IN6")
		(34 "In16.Cu" signal "GND7")
		(2 "B.Cu" signal "BOTTOM")
		(9 "F.Adhes" user "F.Adhesive")
		(11 "B.Adhes" user "B.Adhesive")
		(13 "F.Paste" user "Package Geometry/Pastemask Top")
		(15 "B.Paste" user "Package Geometry/Pastemask Bottom")
		(5 "F.SilkS" user "Ref Des/Silkscreen Top")
		(7 "B.SilkS" user "Ref Des/Silkscreen Bottom")
		(1 "F.Mask" user "Board Geometry/Soldermask Top")
		(3 "B.Mask" user "Board Geometry/Soldermask Bottom")
		(17 "Dwgs.User" user "User.Drawings")
		(19 "Cmts.User" user "User.Comments")
		(21 "Eco1.User" user "User.Eco1")
		(23 "Eco2.User" user "User.Eco2")
		(25 "Edge.Cuts" user "Board Geometry/Outline")
		(27 "Margin" user)
		(31 "F.CrtYd" user "Package Geometry/Place Bound Top")
		(29 "B.CrtYd" user "Package Geometry/Place Bound Bottom")
		(35 "F.Fab" user "Ref Des/Assembly Top")
		(33 "B.Fab" user "Ref Des/Assembly Bottom")
	)
	(footprint ""
		(layer "B.Cu")
		(at 312.978292 -395.148562 90)
		(property "Reference" "C515"
			(at 0 0 90)
			(layer "B.SilkS")
			(hide yes)
			(effects
				(font
					(size 1.27 1.27)
				)
				(justify mirror)
			)
		)
		(property "Value" ""
			(at 0 0 90)
			(layer "B.Fab")
			(effects
				(font
					(size 1.27 1.27)
				)
				(justify mirror)
			)
		)
		(duplicate_pad_numbers_are_jumpers no)
		(fp_line
			(start 0.299974 -0.150114)
			(end -0.299974 -0.150114)
			(stroke
				(width 0.1)
				(type default)
			)
			(layer "B.Fab")
		)
		(fp_line
			(start -0.299974 -0.150114)
			(end -0.299974 0.150114)
			(stroke
				(width 0.1)
				(type default)
			)
			(layer "B.Fab")
		)
		(fp_line
			(start 0.299974 0.150114)
			(end 0.299974 -0.150114)
			(stroke
				(width 0.1)
				(type default)
			)
			(layer "B.Fab")
		)
		(fp_line
			(start -0.299974 0.150114)
			(end 0.299974 0.150114)
			(stroke
				(width 0.1)
				(type default)
			)
			(layer "B.Fab")
		)
		(pad "1" smd rect
			(at 0.2667 0 270)
			(size 0.3048 0.381)
			(layers "B.Cu" "B.Mask" "B.Paste")
			(net "P1V8_CPU0_RT0_1A")
		)
		(pad "2" smd rect
			(at -0.2667 0 270)
			(size 0.3048 0.381)
			(layers "B.Cu" "B.Mask" "B.Paste")
			(net "GND")
		)
	)
	(footprint ""
		(layer "B.Cu")
		(at 113.81486 -34.351468 90)
		(property "Reference" "C6105"
			(at 0 0 90)
			(layer "B.SilkS")
			(hide yes)
			(effects
				(font
					(size 1.27 1.27)
				)
				(justify mirror)
			)
		)
		(property "Value" ""
			(at 0 0 90)
			(layer "B.Fab")
			(effects
				(font
					(size 1.27 1.27)
				)
				(justify mirror)
			)
		)
		(duplicate_pad_numbers_are_jumpers no)
		(fp_line
			(start 1.524 -0.762)
			(end -1.524 -0.762)
			(stroke
				(width 0.1524)
				(type default)
			)
			(layer "B.SilkS")
		)
		(fp_line
			(start -1.524 -0.762)
			(end -1.524 0.762)
			(stroke
				(width 0.1524)
				(type default)
			)
			(layer "B.SilkS")
		)
		(fp_line
			(start 1.524 0.762)
			(end 1.524 -0.762)
			(stroke
				(width 0.1524)
				(type default)
			)
			(layer "B.SilkS")
		)
		(fp_line
			(start -1.524 0.762)
			(end 1.524 0.762)
			(stroke
				(width 0.1524)
				(type default)
			)
			(layer "B.SilkS")
		)
		(fp_line
			(start 1.1049 -0.724916)
			(end 1.1049 0.724916)
			(stroke
				(width 0.1)
				(type default)
			)
			(layer "B.Fab")
		)
		(fp_line
			(start -1.1049 -0.724916)
			(end 1.1049 -0.724916)
			(stroke
				(width 0.1)
				(type default)
			)
			(layer "B.Fab")
		)
		(fp_line
			(start 1.1049 0.724916)
			(end -1.1049 0.724916)
			(stroke
				(width 0.1)
				(type default)
			)
			(layer "B.Fab")
		)
		(fp_line
			(start -1.1049 0.724916)
			(end -1.1049 -0.724916)
			(stroke
				(width 0.1)
				(type default)
			)
			(layer "B.Fab")
		)
		(pad "1" smd rect
			(at 0.889 0 90)
			(size 1.016 1.27)
			(layers "B.Cu" "B.Mask" "B.Paste")
			(net "P1V2_CPU0_USB2_DVDD12")
		)
		(pad "2" smd rect
			(at -0.889 0 90)
			(size 1.016 1.27)
			(layers "B.Cu" "B.Mask" "B.Paste")
			(net "GND")
		)
	)
	(footprint ""
		(layer "B.Cu")
		(at 126.491238 -390.909302 90)
		(property "Reference" "C454"
			(at 0 0 90)
			(layer "B.SilkS")
			(hide yes)
			(effects
				(font
					(size 1.27 1.27)
				)
				(justify mirror)
			)
		)
		(property "Value" ""
			(at 0 0 90)
			(layer "B.Fab")
			(effects
				(font
					(size 1.27 1.27)
				)
				(justify mirror)
			)
		)
		(duplicate_pad_numbers_are_jumpers no)
		(fp_line
			(start 0.299974 -0.150114)
			(end -0.299974 -0.150114)
			(stroke
				(width 0.1)
				(type default)
			)
			(layer "B.Fab")
		)
		(fp_line
			(start -0.299974 -0.150114)
			(end -0.299974 0.150114)
			(stroke
				(width 0.1)
				(type default)
			)
			(layer "B.Fab")
		)
		(fp_line
			(start 0.299974 0.150114)
			(end 0.299974 -0.150114)
			(stroke
				(width 0.1)
				(type default)
			)
			(layer "B.Fab")
		)
		(fp_line
			(start -0.299974 0.150114)
			(end 0.299974 0.150114)
			(stroke
				(width 0.1)
				(type default)
			)
			(layer "B.Fab")
		)
		(pad "1" smd rect
			(at 0.2667 0 270)
			(size 0.3048 0.381)
			(layers "B.Cu" "B.Mask" "B.Paste")
			(net "P0V9_CPU1_RT_2D")
		)
		(pad "2" smd rect
			(at -0.2667 0 270)
			(size 0.3048 0.381)
			(layers "B.Cu" "B.Mask" "B.Paste")
			(net "GND")
		)
	)
	(footprint ""
		(layer "B.Cu")
		(at 454.068688 -13.102844 90)
		(property "Reference" "R3132"
			(at 0 0 90)
			(layer "B.SilkS")
			(hide yes)
			(effects
				(font
					(size 1.27 1.27)
				)
				(justify mirror)
			)
		)
		(property "Value" ""
			(at 0 0 90)
			(layer "B.Fab")
			(effects
				(font
					(size 1.27 1.27)
				)
				(justify mirror)
			)
		)
		(duplicate_pad_numbers_are_jumpers no)
		(fp_line
			(start 0.7874 -0.4064)
			(end -0.7874 -0.4064)
			(stroke
				(width 0.1524)
				(type default)
			)
			(layer "B.SilkS")
		)
		(fp_line
			(start -0.7874 -0.4064)
			(end -0.7874 0.4064)
			(stroke
				(width 0.1524)
				(type default)
			)
			(layer "B.SilkS")
		)
		(fp_line
			(start 0.7874 0.4064)
			(end 0.7874 -0.4064)
			(stroke
				(width 0.1524)
				(type default)
			)
			(layer "B.SilkS")
		)
		(fp_line
			(start -0.7874 0.4064)
			(end 0.7874 0.4064)
			(stroke
				(width 0.1524)
				(type default)
			)
			(layer "B.SilkS")
		)
		(fp_line
			(start 0.67945 -0.305054)
			(end 0.12065 -0.305054)
			(stroke
				(width 0.1)
				(type default)
			)
			(layer "B.Fab")
		)
		(fp_line
			(start 0.12065 -0.305054)
			(end 0.12065 -0.2794)
			(stroke
				(width 0.1)
				(type default)
			)
			(layer "B.Fab")
		)
		(fp_line
			(start -0.12065 -0.3048)
			(end -0.67945 -0.3048)
			(stroke
				(width 0.1)
				(type default)
			)
			(layer "B.Fab")
		)
		(fp_line
			(start -0.67945 -0.3048)
			(end -0.67945 0.3048)
			(stroke
				(width 0.1)
				(type default)
			)
			(layer "B.Fab")
		)
		(fp_line
			(start 0.12065 -0.2794)
			(end -0.12065 -0.2794)
			(stroke
				(width 0.1)
				(type default)
			)
			(layer "B.Fab")
		)
		(fp_line
			(start -0.12065 -0.2794)
			(end -0.12065 -0.3048)
			(stroke
				(width 0.1)
				(type default)
			)
			(layer "B.Fab")
		)
		(fp_line
			(start 0.12065 0.2794)
			(end 0.12065 0.3048)
			(stroke
				(width 0.1)
				(type default)
			)
			(layer "B.Fab")
		)
		(fp_line
			(start -0.120396 0.2794)
			(end 0.12065 0.2794)
			(stroke
				(width 0.1)
				(type default)
			)
			(layer "B.Fab")
		)
		(fp_line
			(start 0.67945 0.3048)
			(end 0.67945 -0.305054)
			(stroke
				(width 0.1)
				(type default)
			)
			(layer "B.Fab")
		)
		(fp_line
			(start 0.12065 0.3048)
			(end 0.67945 0.3048)
			(stroke
				(width 0.1)
				(type default)
			)
			(layer "B.Fab")
		)
		(fp_line
			(start -0.120396 0.3048)
			(end -0.120396 0.2794)
			(stroke
				(width 0.1)
				(type default)
			)
			(layer "B.Fab")
		)
		(fp_line
			(start -0.67945 0.3048)
			(end -0.120396 0.3048)
			(stroke
				(width 0.1)
				(type default)
			)
			(layer "B.Fab")
		)
		(pad "1" smd circle
			(at 0.40005 0 270)
			(size 0 0)
			(layers "B.Cu" "B.Mask" "B.Paste")
			(net "GND")
		)
		(pad "2" smd circle
			(at -0.40005 0 270)
			(size 0 0)
			(layers "B.Cu" "B.Mask" "B.Paste")
			(net "FM_OCP_SFF_PWR_GOOD")
		)
	)
)
